(kicad_pcb
	(version 20260206)
	(generator "pcbnew")
	(generator_version "10.0")
	(general
		(thickness 1.6)
		(legacy_teardrops no)
	)
	(paper "A4")
	(title_block
		(title "Wiwynn_Tioga_Pass_MB.brd")
		(comment 1 "Tioga Pass / footprints 2105-2111 of 4770")
	)
	(layers
		(0 "F.Cu" signal "TOP")
		(4 "In1.Cu" signal "L2GND")
		(6 "In2.Cu" signal "L3")
		(8 "In3.Cu" signal "L4GND")
		(10 "In4.Cu" signal "L5")
		(12 "In5.Cu" signal "L6GND")
		(14 "In6.Cu" signal "L7VCC")
		(16 "In7.Cu" signal "L8VCC")
		(18 "In8.Cu" signal "L9GND")
		(20 "In9.Cu" signal "L10")
		(22 "In10.Cu" signal "L11GND")
		(24 "In11.Cu" signal "L12")
		(26 "In12.Cu" signal "L13GND")
		(2 "B.Cu" signal "BOTTOM")
		(9 "F.Adhes" user "F.Adhesive")
		(11 "B.Adhes" user "B.Adhesive")
		(13 "F.Paste" user "Package Geometry/Pastemask Top")
		(15 "B.Paste" user "Package Geometry/Pastemask Bottom")
		(5 "F.SilkS" user "Ref Des/Silkscreen Top")
		(7 "B.SilkS" user "Ref Des/Silkscreen Bottom")
		(1 "F.Mask" user "Board Geometry/Soldermask Top")
		(3 "B.Mask" user "Board Geometry/Soldermask Bottom")
		(17 "Dwgs.User" user "User.Drawings")
		(19 "Cmts.User" user "User.Comments")
		(21 "Eco1.User" user "User.Eco1")
		(23 "Eco2.User" user "User.Eco2")
		(25 "Edge.Cuts" user "Board Geometry/Outline")
		(27 "Margin" user)
		(31 "F.CrtYd" user "Package Geometry/Place Bound Top")
		(29 "B.CrtYd" user "Package Geometry/Place Bound Bottom")
		(35 "F.Fab" user "Ref Des/Assembly Top")
		(33 "B.Fab" user "Ref Des/Assembly Bottom")
	)
	(footprint ""
		(layer "F.Cu")
		(at 321.16522 -120.53316 -90)
		(property "Reference" "C840"
			(at -0.8382 -0.67818 270)
			(unlocked yes)
			(layer "F.SilkS")
			(effects
				(font
					(size 0.4064 0.254)
					(thickness 0.1524)
				)
				(justify left)
			)
		)
		(property "Value" ""
			(at 0 0 270)
			(layer "F.Fab")
			(effects
				(font
					(size 1.27 1.27)
				)
			)
		)
		(duplicate_pad_numbers_are_jumpers no)
		(fp_poly
			(pts
				(xy 0.3048 -0.1016) (xy 0.3048 0.9906) (xy -0.3048 0.9906) (xy -0.3048 -0.1016)
			)
			(stroke
				(width 0)
				(type default)
			)
			(fill no)
			(layer "F.CrtYd")
		)
		(fp_line
			(start -0.3048 0.9906)
			(end 0.3048 0.9906)
			(stroke
				(width 0.1)
				(type default)
			)
			(layer "F.Fab")
		)
		(fp_line
			(start 0.3048 0.9906)
			(end 0.3048 -0.1016)
			(stroke
				(width 0.1)
				(type default)
			)
			(layer "F.Fab")
		)
		(fp_line
			(start -0.3048 -0.1016)
			(end -0.3048 0.9906)
			(stroke
				(width 0.1)
				(type default)
			)
			(layer "F.Fab")
		)
		(fp_line
			(start 0.3048 -0.1016)
			(end -0.3048 -0.1016)
			(stroke
				(width 0.1)
				(type default)
			)
			(layer "F.Fab")
		)
		(pad "1" smd rect
			(at 0 0 270)
			(size 0.508 0.508)
			(layers "F.Cu" "F.Mask" "F.Paste")
			(net "P3E_CPU0_PE1_PCH_TXN<12>")
		)
		(pad "2" smd rect
			(at 0 0.889 270)
			(size 0.508 0.508)
			(layers "F.Cu" "F.Mask" "F.Paste")
			(net "P3E_CPU0_PE1_PCH_CON_TXN<12>")
		)
		(zone
			(layer "F.Cu")
			(hatch none 0.5)
			(connect_pads
				(clearance 0)
			)
			(min_thickness 0.25)
			(keepout
				(tracks not_allowed)
				(vias allowed)
				(pads allowed)
				(copperpour not_allowed)
				(footprints allowed)
			)
			(placement
				(enabled no)
				(sheetname "")
			)
			(fill
				(thermal_gap 0.5)
				(thermal_bridge_width 0.5)
				(island_removal_mode 0)
			)
			(polygon
				(pts
					(xy 320.53022 -120.78716) (xy 320.53022 -120.27916) (xy 320.91122 -120.27916) (xy 320.91122 -120.78716)
				)
			)
		)
		(zone
			(layer "F.Cu")
			(hatch none 0.5)
			(connect_pads
				(clearance 0)
			)
			(min_thickness 0.25)
			(keepout
				(tracks allowed)
				(vias not_allowed)
				(pads allowed)
				(copperpour not_allowed)
				(footprints allowed)
			)
			(placement
				(enabled no)
				(sheetname "")
			)
			(fill
				(thermal_gap 0.5)
				(thermal_bridge_width 0.5)
				(island_removal_mode 0)
			)
			(polygon
				(pts
					(xy 320.91122 -120.78716) (xy 320.91122 -120.27916) (xy 320.53022 -120.27916) (xy 320.53022 -120.78716)
				)
			)
		)
	)
	(footprint ""
		(layer "F.Cu")
		(at 33.093152 -68.525644 90)
		(property "Reference" "C1D34"
			(at 0 0 90)
			(layer "F.SilkS")
			(hide yes)
			(effects
				(font
					(size 1.27 1.27)
				)
			)
		)
		(property "Value" ""
			(at 0 0 90)
			(layer "F.Fab")
			(effects
				(font
					(size 1.27 1.27)
				)
			)
		)
		(duplicate_pad_numbers_are_jumpers no)
		(fp_rect
			(start 0.3048 0.9906)
			(end -0.3048 -0.1016)
			(stroke
				(width 0)
				(type default)
			)
			(fill no)
			(layer "F.CrtYd")
		)
		(fp_line
			(start 0.3048 -0.1016)
			(end -0.3048 -0.1016)
			(stroke
				(width 0.1)
				(type default)
			)
			(layer "F.Fab")
		)
		(fp_line
			(start -0.3048 -0.1016)
			(end -0.3048 0.9906)
			(stroke
				(width 0.1)
				(type default)
			)
			(layer "F.Fab")
		)
		(fp_line
			(start 0.3048 0.9906)
			(end 0.3048 -0.1016)
			(stroke
				(width 0.1)
				(type default)
			)
			(layer "F.Fab")
		)
		(fp_line
			(start -0.3048 0.9906)
			(end 0.3048 0.9906)
			(stroke
				(width 0.1)
				(type default)
			)
			(layer "F.Fab")
		)
		(pad "1" smd rect
			(at 0 0 90)
			(size 0.508 0.508)
			(layers "F.Cu" "F.Mask" "F.Paste")
			(net "VR_FET_SW_P12V_STBY_PVCCIN_CPU1")
		)
		(pad "2" smd rect
			(at 0 0.889 90)
			(size 0.508 0.508)
			(layers "F.Cu" "F.Mask" "F.Paste")
			(net "GND")
		)
		(zone
			(layer "F.Cu")
			(hatch none 0.5)
			(connect_pads
				(clearance 0)
			)
			(min_thickness 0.25)
			(keepout
				(tracks allowed)
				(vias not_allowed)
				(pads allowed)
				(copperpour not_allowed)
				(footprints allowed)
			)
			(placement
				(enabled no)
				(sheetname "")
			)
			(fill
				(thermal_gap 0.5)
				(thermal_bridge_width 0.5)
				(island_removal_mode 0)
			)
			(polygon
				(pts
					(xy 33.728152 -68.779644) (xy 33.347152 -68.779644) (xy 33.347152 -68.271644) (xy 33.728152 -68.271644)
				)
			)
		)
		(zone
			(layer "F.Cu")
			(hatch none 0.5)
			(connect_pads
				(clearance 0)
			)
			(min_thickness 0.25)
			(keepout
				(tracks not_allowed)
				(vias allowed)
				(pads allowed)
				(copperpour not_allowed)
				(footprints allowed)
			)
			(placement
				(enabled no)
				(sheetname "")
			)
			(fill
				(thermal_gap 0.5)
				(thermal_bridge_width 0.5)
				(island_removal_mode 0)
			)
			(polygon
				(pts
					(xy 33.728152 -68.779644) (xy 33.347152 -68.779644) (xy 33.347152 -68.271644) (xy 33.728152 -68.271644)
				)
			)
		)
	)
	(footprint ""
		(layer "F.Cu")
		(at 477.8756 -45.1739 180)
		(property "Reference" "C9E7"
			(at 0 0 180)
			(layer "F.SilkS")
			(hide yes)
			(effects
				(font
					(size 1.27 1.27)
				)
			)
		)
		(property "Value" ""
			(at 0 0 180)
			(layer "F.Fab")
			(effects
				(font
					(size 1.27 1.27)
				)
			)
		)
		(duplicate_pad_numbers_are_jumpers no)
		(fp_poly
			(pts
				(xy 0.3048 -0.1016) (xy 0.3048 0.9906) (xy -0.3048 0.9906) (xy -0.3048 -0.1016)
			)
			(stroke
				(width 0)
				(type default)
			)
			(fill no)
			(layer "F.CrtYd")
		)
		(fp_line
			(start 0.3048 0.9906)
			(end 0.3048 -0.1016)
			(stroke
				(width 0.1)
				(type default)
			)
			(layer "F.Fab")
		)
		(fp_line
			(start 0.3048 -0.1016)
			(end -0.3048 -0.1016)
			(stroke
				(width 0.1)
				(type default)
			)
			(layer "F.Fab")
		)
		(fp_line
			(start -0.3048 0.9906)
			(end 0.3048 0.9906)
			(stroke
				(width 0.1)
				(type default)
			)
			(layer "F.Fab")
		)
		(fp_line
			(start -0.3048 -0.1016)
			(end -0.3048 0.9906)
			(stroke
				(width 0.1)
				(type default)
			)
			(layer "F.Fab")
		)
		(pad "1" smd rect
			(at 0 0 180)
			(size 0.508 0.508)
			(layers "F.Cu" "F.Mask" "F.Paste")
			(net "A_CTOP")
		)
		(pad "2" smd rect
			(at 0 0.889 180)
			(size 0.508 0.508)
			(layers "F.Cu" "F.Mask" "F.Paste")
			(net "A_CBOT")
		)
		(zone
			(layer "F.Cu")
			(hatch none 0.5)
			(connect_pads
				(clearance 0)
			)
			(min_thickness 0.25)
			(keepout
				(tracks not_allowed)
				(vias allowed)
				(pads allowed)
				(copperpour not_allowed)
				(footprints allowed)
			)
			(placement
				(enabled no)
				(sheetname "")
			)
			(fill
				(thermal_gap 0.5)
				(thermal_bridge_width 0.5)
				(island_removal_mode 0)
			)
			(polygon
				(pts
					(xy 478.1296 -45.8089) (xy 477.6216 -45.8089) (xy 477.6216 -45.4279) (xy 478.1296 -45.4279)
				)
			)
		)
		(zone
			(layer "F.Cu")
			(hatch none 0.5)
			(connect_pads
				(clearance 0)
			)
			(min_thickness 0.25)
			(keepout
				(tracks allowed)
				(vias not_allowed)
				(pads allowed)
				(copperpour not_allowed)
				(footprints allowed)
			)
			(placement
				(enabled no)
				(sheetname "")
			)
			(fill
				(thermal_gap 0.5)
				(thermal_bridge_width 0.5)
				(island_removal_mode 0)
			)
			(polygon
				(pts
					(xy 478.1296 -45.4279) (xy 477.6216 -45.4279) (xy 477.6216 -45.8089) (xy 478.1296 -45.8089)
				)
			)
		)
	)
	(footprint ""
		(layer "F.Cu")
		(at 404.9522 -128.3335)
		(property "Reference" "C8B4"
			(at 0 0 0)
			(layer "F.SilkS")
			(hide yes)
			(effects
				(font
					(size 1.27 1.27)
				)
			)
		)
		(property "Value" ""
			(at 0 0 0)
			(layer "F.Fab")
			(effects
				(font
					(size 1.27 1.27)
				)
			)
		)
		(duplicate_pad_numbers_are_jumpers no)
		(fp_poly
			(pts
				(xy -0.4953 -0.2032) (xy 0.4953 -0.2032) (xy 0.4953 1.6002) (xy -0.4953 1.6002)
			)
			(stroke
				(width 0)
				(type default)
			)
			(fill no)
			(layer "F.CrtYd")
		)
		(fp_line
			(start -0.4953 -0.2032)
			(end 0.4953 -0.2032)
			(stroke
				(width 0.1)
				(type default)
			)
			(layer "F.Fab")
		)
		(fp_line
			(start -0.4953 1.6002)
			(end -0.4953 -0.2032)
			(stroke
				(width 0.1)
				(type default)
			)
			(layer "F.Fab")
		)
		(fp_line
			(start 0.4953 -0.2032)
			(end 0.4953 1.6002)
			(stroke
				(width 0.1)
				(type default)
			)
			(layer "F.Fab")
		)
		(fp_line
			(start 0.4953 1.6002)
			(end -0.4953 1.6002)
			(stroke
				(width 0.1)
				(type default)
			)
			(layer "F.Fab")
		)
		(pad "1" smd rect
			(at 0 0)
			(size 0.762 0.889)
			(layers "F.Cu" "F.Mask" "F.Paste")
			(net "P1V8_PCH_STBY")
		)
		(pad "2" smd rect
			(at 0 1.397)
			(size 0.762 0.889)
			(layers "F.Cu" "F.Mask" "F.Paste")
			(net "GND")
		)
		(zone
			(layer "F.Cu")
			(hatch none 0.5)
			(connect_pads
				(clearance 0)
			)
			(min_thickness 0.25)
			(keepout
				(tracks not_allowed)
				(vias allowed)
				(pads allowed)
				(copperpour not_allowed)
				(footprints allowed)
			)
			(placement
				(enabled no)
				(sheetname "")
			)
			(fill
				(thermal_gap 0.5)
				(thermal_bridge_width 0.5)
				(island_removal_mode 0)
			)
			(polygon
				(pts
					(xy 404.5712 -127.889) (xy 405.3332 -127.889) (xy 405.3332 -127.381) (xy 404.5712 -127.381)
				)
			)
		)
	)
	(footprint ""
		(layer "F.Cu")
		(at 174.244 -141.1605 90)
		(property "Reference" "C4A16"
			(at 0 0 90)
			(layer "F.SilkS")
			(hide yes)
			(effects
				(font
					(size 1.27 1.27)
				)
			)
		)
		(property "Value" ""
			(at 0 0 90)
			(layer "F.Fab")
			(effects
				(font
					(size 1.27 1.27)
				)
			)
		)
		(duplicate_pad_numbers_are_jumpers no)
		(fp_poly
			(pts
				(xy 0.3048 -0.1016) (xy 0.3048 0.9906) (xy -0.3048 0.9906) (xy -0.3048 -0.1016)
			)
			(stroke
				(width 0)
				(type default)
			)
			(fill no)
			(layer "F.CrtYd")
		)
		(fp_line
			(start 0.3048 -0.1016)
			(end -0.3048 -0.1016)
			(stroke
				(width 0.1)
				(type default)
			)
			(layer "F.Fab")
		)
		(fp_line
			(start -0.3048 -0.1016)
			(end -0.3048 0.9906)
			(stroke
				(width 0.1)
				(type default)
			)
			(layer "F.Fab")
		)
		(fp_line
			(start 0.3048 0.9906)
			(end 0.3048 -0.1016)
			(stroke
				(width 0.1)
				(type default)
			)
			(layer "F.Fab")
		)
		(fp_line
			(start -0.3048 0.9906)
			(end 0.3048 0.9906)
			(stroke
				(width 0.1)
				(type default)
			)
			(layer "F.Fab")
		)
		(pad "1" smd rect
			(at 0 0 90)
			(size 0.508 0.508)
			(layers "F.Cu" "F.Mask" "F.Paste")
			(net "VR_PVPP_KLM_PHASE")
		)
		(pad "2" smd rect
			(at 0 0.889 90)
			(size 0.508 0.508)
			(layers "F.Cu" "F.Mask" "F.Paste")
			(net "VR_PVPP_KLM_SNUB")
		)
		(zone
			(layer "F.Cu")
			(hatch none 0.5)
			(connect_pads
				(clearance 0)
			)
			(min_thickness 0.25)
			(keepout
				(tracks allowed)
				(vias not_allowed)
				(pads allowed)
				(copperpour not_allowed)
				(footprints allowed)
			)
			(placement
				(enabled no)
				(sheetname "")
			)
			(fill
				(thermal_gap 0.5)
				(thermal_bridge_width 0.5)
				(island_removal_mode 0)
			)
			(polygon
				(pts
					(xy 174.498 -140.9065) (xy 174.498 -141.4145) (xy 174.879 -141.4145) (xy 174.879 -140.9065)
				)
			)
		)
		(zone
			(layer "F.Cu")
			(hatch none 0.5)
			(connect_pads
				(clearance 0)
			)
			(min_thickness 0.25)
			(keepout
				(tracks not_allowed)
				(vias allowed)
				(pads allowed)
				(copperpour not_allowed)
				(footprints allowed)
			)
			(placement
				(enabled no)
				(sheetname "")
			)
			(fill
				(thermal_gap 0.5)
				(thermal_bridge_width 0.5)
				(island_removal_mode 0)
			)
			(polygon
				(pts
					(xy 174.879 -140.9065) (xy 174.879 -141.4145) (xy 174.498 -141.4145) (xy 174.498 -140.9065)
				)
			)
		)
	)
	(footprint ""
		(layer "F.Cu")
		(at 200.604628 -93.577918 -90)
		(property "Reference" "RT39"
			(at 0 0 270)
			(layer "F.SilkS")
			(hide yes)
			(effects
				(font
					(size 1.27 1.27)
				)
			)
		)
		(property "Value" "*"
			(at -0.0254 -2.6289 270)
			(unlocked yes)
			(layer "F.Fab")
			(hide yes)
			(effects
				(font
					(size 1.27 1.016)
					(thickness 0.1524)
				)
			)
		)
		(property "Device Type" "1R3F-GP_RCL_GP-1R3F-GP,64.1R00A"
			(at -0.0254 -4.1529 270)
			(unlocked yes)
			(layer "F.Fab")
			(hide yes)
			(effects
				(font
					(size 1.27 1.016)
					(thickness 0.1524)
				)
			)
		)
		(duplicate_pad_numbers_are_jumpers no)
		(fp_line
			(start -0.4826 0)
			(end -0.2032 0)
			(stroke
				(width 0.2032)
				(type default)
			)
			(layer "F.SilkS")
		)
		(fp_line
			(start 0.2032 0)
			(end 0.4826 0)
			(stroke
				(width 0.2032)
				(type default)
			)
			(layer "F.SilkS")
		)
		(fp_rect
			(start -0.5842 1.3335)
			(end 0.5842 -1.3335)
			(stroke
				(width 0)
				(type default)
			)
			(fill no)
			(layer "F.CrtYd")
		)
		(fp_rect
			(start -0.5842 1.3335)
			(end 0.5842 -1.3335)
			(stroke
				(width 0)
				(type default)
			)
			(fill no)
			(layer "F.Fab")
		)
		(pad "1" smd custom
			(at 0 -0.762 270)
			(size 0.2159 0.2159)
			(layers "F.Cu" "F.Mask" "F.Paste")
			(net "VR_PVSA_CPU0_PHASE_SW_RC")
			(options
				(clearance outline)
				(anchor circle)
			)
			(primitives
				(gr_poly
					(pts
						(arc
							(start -0.3302 -0.4318)
							(mid -0.402042 -0.402042)
							(end -0.4318 -0.3302)
						)
						(arc
							(start -0.4318 0.3302)
							(mid -0.402042 0.402042)
							(end -0.3302 0.4318)
						)
						(arc
							(start 0.3302 0.4318)
							(mid 0.402042 0.402042)
							(end 0.4318 0.3302)
						)
						(arc
							(start 0.4318 -0.3302)
							(mid 0.402042 -0.402042)
							(end 0.3302 -0.4318)
						)
					)
					(width 0)
					(fill yes)
				)
			)
		)
		(pad "2" smd custom
			(at 0 0.762 270)
			(size 0.2159 0.2159)
			(layers "F.Cu" "F.Mask" "F.Paste")
			(net "GND")
			(options
				(clearance outline)
				(anchor circle)
			)
			(primitives
				(gr_poly
					(pts
						(arc
							(start -0.3302 -0.4318)
							(mid -0.402042 -0.402042)
							(end -0.4318 -0.3302)
						)
						(arc
							(start -0.4318 0.3302)
							(mid -0.402042 0.402042)
							(end -0.3302 0.4318)
						)
						(arc
							(start 0.3302 0.4318)
							(mid 0.402042 0.402042)
							(end 0.4318 0.3302)
						)
						(arc
							(start 0.4318 -0.3302)
							(mid 0.402042 -0.402042)
							(end 0.3302 -0.4318)
						)
					)
					(width 0)
					(fill yes)
				)
			)
		)
	)
	(footprint ""
		(layer "F.Cu")
		(at 166.9415 -0.77978 -90)
		(property "Reference" "U4G1"
			(at -3.00482 2.09423 90)
			(unlocked yes)
			(layer "F.SilkS")
			(effects
				(font
					(size 0.7874 0.5842)
					(thickness 0.1524)
				)
			)
		)
		(property "Value" ""
			(at 0 0 270)
			(layer "F.Fab")
			(effects
				(font
					(size 1.27 1.27)
				)
			)
		)
		(duplicate_pad_numbers_are_jumpers no)
		(fp_line
			(start 3.225038 2.52476)
			(end 1.348486 2.52476)
			(stroke
				(width 0.1524)
				(type default)
			)
			(layer "F.SilkS")
		)
		(fp_line
			(start 3.225292 -0.57404)
			(end 1.352804 -0.57404)
			(stroke
				(width 0.1524)
				(type default)
			)
			(layer "F.SilkS")
		)
		(fp_circle
			(center -1.454404 -0.556514)
			(end -1.454404 -0.683514)
			(stroke
				(width 0.254)
				(type default)
			)
			(fill no)
			(layer "F.SilkS")
		)
		(fp_poly
			(pts
				(xy 0.7366 -0.57404) (xy 3.8354 -0.57404) (xy 3.8354 2.52476) (xy 0.7366 2.52476)
			)
			(stroke
				(width 0)
				(type default)
			)
			(fill no)
			(layer "F.CrtYd")
		)
		(fp_line
			(start 0.7366 2.52476)
			(end 0.7366 -0.57404)
			(stroke
				(width 0.1)
				(type default)
			)
			(layer "F.Fab")
		)
		(fp_line
			(start 3.8354 2.52476)
			(end 0.7366 2.52476)
			(stroke
				(width 0.1)
				(type default)
			)
			(layer "F.Fab")
		)
		(fp_line
			(start 0.7366 -0.57404)
			(end 3.8354 -0.57404)
			(stroke
				(width 0.1)
				(type default)
			)
			(layer "F.Fab")
		)
		(fp_line
			(start 3.8354 -0.57404)
			(end 3.8354 2.52476)
			(stroke
				(width 0.1)
				(type default)
			)
			(layer "F.Fab")
		)
		(fp_circle
			(center -1.454404 -0.556514)
			(end -1.454404 -0.683514)
			(stroke
				(width 0.254)
				(type default)
			)
			(fill no)
			(layer "F.Fab")
		)
		(pad "1" smd rect
			(at 0 0 270)
			(size 1.778 0.4572)
			(layers "F.Cu" "F.Mask" "F.Paste")
			(net "PVCCIO_CPU1")
		)
		(pad "2" smd rect
			(at 0 0.65024 270)
			(size 1.778 0.4572)
			(layers "F.Cu" "F.Mask" "F.Paste")
			(net "SMB_DDR_GHJ_SCL_G")
		)
		(pad "3" smd rect
			(at 0 1.30048 270)
			(size 1.778 0.4572)
			(layers "F.Cu" "F.Mask" "F.Paste")
			(net "SMB_DDR_GHJ_SDA_G")
		)
		(pad "4" smd rect
			(at 0 1.95072 270)
			(size 1.778 0.4572)
			(layers "F.Cu" "F.Mask" "F.Paste")
			(net "GND")
		)
		(pad "5" smd rect
			(at 4.572 1.95072 270)
			(size 1.778 0.4572)
			(layers "F.Cu" "F.Mask" "F.Paste")
			(net "TP_SMB_DDR_GHJ_EN")
		)
		(pad "6" smd rect
			(at 4.572 1.30048 270)
			(size 1.778 0.4572)
			(layers "F.Cu" "F.Mask" "F.Paste")
			(net "SMB_DDR_GHJ_VPP_SDA_R")
		)
		(pad "7" smd rect
			(at 4.572 0.65024 270)
			(size 1.778 0.4572)
			(layers "F.Cu" "F.Mask" "F.Paste")
			(net "SMB_DDR_GHJ_VPP_SCL_R")
		)
		(pad "8" smd rect
			(at 4.572 0 270)
			(size 1.778 0.4572)
			(layers "F.Cu" "F.Mask" "F.Paste")
			(net "PVPP_GHJ")
		)
	)
)
